 
 
Open CloudServer OCS 
Tray Mezzanine Specification 
Version 2.0 
 
 
 
 
 
Author: 
Mark Shaw, Director of Hardware Engineering, Microsoft 
 
 



Open Compute Project  Open CloudServer OCS Tray Mezzanine 
http://opencompute.org ii 
Revision History 
Date Description 
10/30/2014 Version 2.0 
 
  



Open Compute Project  Open CloudServer OCS Tray Mezzanine 
http://opencompute.org iii 
 
© 2014 Microsoft Corporation. 
As of October 30, 2014, the following persons or entities have made this Specification available under the Open Web 
Foundation Final Specification Agreement (OWFa 1.0), which is available at http://www.openwebfoundation.org/legal/the-owf-
1-0-agreements/owfa-1-0 
Microsoft Corporation.  
You can review the signed copies of the Open Web Foundation Agreement Version 1.0 for this Specification at 
http://opencompute.org/licensing/, which may also include additional parties to those listed above. 
Your use of this Specification may be subject to other third party rights. THIS SPECIFICATION IS PROVIDED "AS IS." The 
contributors expressly disclaim any warranties (express, implied, or otherwise), including implied warranties of merchantability, 
noninfringement, fitness for a particular purpose, or title, related to the Specification. The entire risk as to implementing or 
otherwise using the Specification is assumed by the Specification implementer and user. IN NO EVENT WILL ANY PARTY BE 
LIABLE TO ANY OTHER PARTY FOR LOST PROFITS OR ANY FORM OF INDIRECT, SPECIAL, INCIDENTAL, OR CONSEQUENTIAL 
DAMAGES OF ANY CHARACTER FROM ANY CAUSES OF ACTION OF ANY KIND WITH RESPECT TO THIS SPECIFICATION OR ITS 
GOVERNING AGREEMENT, WHETHER BASED ON BREACH OF CONTRACT, TORT (INCLUDING NEGLIGENCE), OR OTHERWISE, AND 
WHETHER OR NOT THE OTHER PARTY HAS BEEN ADVISED OF THE POSSIBILITY OF SUCH DAMAGE. 
CONTRIBUTORS AND LICENSORS OF THIS SPECIFICATION MAY HAVE MENTIONED CERTAIN TECHNOLOGIES THAT ARE MERELY 
REFERENCED WITHIN THIS SPECIFICATION AND NOT LICENSED UNDER THE OWF CLA OR OWFa. THE FOLLOWING IS A LIST OF 
MERELY REFERENCED TECHNOLOGY: INTELLIGENT PLATFORM MANAGEMENT INTERFACE (IPMI), I2C TRADEMARK OF PHILLIPS 
SEMICONDUCTOR. IMPLEMENTATION OF THESE TECHNOLOGIES MAY BE SUBJECT TO THEIR OWN LEGAL TERMS.  



 
iv October 30, 2014 
 
 
Contents 
1 Summary ....................................................................................................................................................... 1 
2 Interface Connector ....................................................................................................................................... 2 
2.1 Signal Definitions .......................................................................................................................................... 3 
2.2 Connector Pinout .......................................................................................................................................... 5 
2.3 Power ........................................................................................................................................................... 6 
3 Mechanical Control Outline ........................................................................................................................... 6 
4 CAD Model Capture ....................................................................................................................................... 7 
5 Thermal Specification .................................................................................................................................... 8 
6 Standoffs and Screws for Assembly ............................................................................................................... 9 
 
Table of Figures 
Figure 1: OCS tray mezzanine card Model A ................................................................................................. 1 
Figure 2: OCS tray mezzanine card Model B ................................................................................................. 2 
Figure 3: Model A connector stackup example ............................................................................................ 3 
Figure 4: Drawing of Model A card ............................................................................................................... 6 
Figure 5: Drawing of Model B card ............................................................................................................... 7 
Figure 6: View from front of Model A and Model B plugged into side-by-side blades ................................ 8 
Figure 7: View from inside of Model A and Model B plugged into side-by-side blades ............................... 8 
Table of Tables 
Table 1: Connector manufacturing part numbers ........................................................................................ 2 
Table 2: Tray mezzanine connector signal definitions .................................................................................. 3 
Table 3: PCIe bifurcation mapping ................................................................................................................ 4 
Table 4: Tray mezzanine connector pinout................................................................................................... 5 
 
 



Open Compute Project  Open CloudServer OCS Tray Mezzanine 
http://opencompute.org 1 
1 Summary 
This specification, Open CloudServer OCS Tray Mezzanine Version 2.0, describes the physical and 
interface requirements for the Open CloudServer (OCS)  tray mezzanine card. The mezzanine card 
will be installed on the tray backplane and will have a Peripheral Component Interconnect Express 
(PCIe) x16 Gen3 interface. This interface can either be used as one x16, two x8, or four x4 channels.  
Note that this specification does not cover the functional or features requirements for the 
mezzanine cards that will be developed for this project. 
There are two mechanical specifications for the mezzanine card: 
 Model A provides a 17.5mm stack height and a 13mm top side height allowance. 
 Model B provides a 15.5mm stack height and a 15mm top side height allowance. 
Figure 1 shows Model A of the OCS tray mezzanine card. 
 
Figure 1: OCS tray mezzanine card Model A 
Figure 2 shows Model B of the OCS tray mezzanine card. 


 
2 October 30, 2014 
 
 
Figure 2: OCS tray mezzanine card Model B 
2 Interface Connector 
The connector interfaces between the tray mezzanine card and the tray backplane use the Samtec 
SEARAY solution. The tray backplane uses a Samtec SEAF (female) connector and the tray 
mezzanine card uses a Samtec SEAM (male) connector. Table 1 lists the manufacturing part 
numbers (MPNs) for Model A and Model B cards. Note that the mating tray backplane SEAF 
connector is fixed and will always be SEAF-20-06.5-S-08-2-A-K-TR; only the mezzanine card can 
vary. 
Table 1: Connector manufacturing part numbers 
Model Manufacturer Mezzanine card connector MPN Mating (MB) connector MPN 
A Samtec SEAM-20-11.0-S-08-2-A-K-TR 
(or equivalent) 
SEAF-20-06.5-S-08-2-A-K-TR 
(or equivalent) 
B Samtec SEAM-20-9.0-S-08-2-A-K-TR 
(or equivalent) 
SEAF-20-06.5-S-08-2-A-K-TR 
(or equivalent) 
Figure 3 shows an example of a stackup for a Model A card, with a 17.5mm stack height with a 
6.5mm SEAF connector and an 11mm SEAM connector. In this configuration, it is expected that 
taller components would be placed on the top side of the printed circuit board (PCB). Note that this 
is an example; a different height SEAM can be used depending on the tray mezzanine back side 
keepout requirements and the required height to clear obstructions on the tray backplane. See 
Section 3 of this specification for more detailed information. 


Open Compute Project  Open CloudServer OCS Tray Mezzanine 
http://opencompute.org 3 
 
SEAF
Tray Mezzanine PCB
Tray Backplane PCB
6.5mm
SEAM11mm
17.5mm
Airmax
Connector
Device
Heatsink
Backside Keepout
 
Figure 3: Model A connector stackup example 
2.1 Signal Definitions 
Table 2 defines the signals used in the tray backplane interface. 
Table 2: Tray mezzanine connector signal definitions 
Bus type I/O Logic Description 
PCIE_B2T_TX_DP/N[15:0] I 
Current-
mode 
logic 
(CML) 
PCIe Gen3 Transmit from blade to tray mezzanine 
card through tray backplane 
PCIE_T2B_RX_DP/N[15:0] O CML PCIe Gen3 Receive from tray mezzanine card to 
blade through tray backplane 
CLK_100M_P/N[3:0] I CML PCIe Gen3 Clock from blade to tray mezzanine card 
through tray backplane 
PCIE_RESET_N[3:0] I 3.3V PCIe Reset from blade to tray mezzanine card 
through tray backplane 
PCIE_WAKE_N O 3.3V PCIe Wake from blade to tray mezzanine card 
through tray backplane 
PCIE_CFG_ID[1:0] O 3.3V 
PCIe Configuration ID from tray mezzanine card to 
blade through tray backplane 
Motherboard shall have 100k pull-up resistors on 
both pins 



 
4 October 30, 2014 
 
Bus type I/O Logic Description 
Mezzanine card shall place 1k pull-down resistors 
for the desired configuration 
00 = 1x16 bifurcation 
01 = 2 x8 bifurcation 
10 = 4 x4 bifurcation 
11 = N/A 
MEZZ_EN I 3.3V 3.3V Power Enable from blade to tray mezzanine 
card through tray backplane 
MEZZ_PRESENT_N O 3.3V 
Present signal from tray mezzanine card to blade 
through tray backplane 
Should be tied to GND on the tray mezzanine card 
MEZZ_SCL I 3.3V I2C Clock from blade to tray mezzanine card 
through tray backplane 
MEZZ_SDA I/O 3.3V I2C Data from blade to tray mezzanine card through 
tray backplane 
P12_MEZZ I 12V 
12V Power from blade to tray mezzanine card 
through tray backplane 
Max power is 36W 
Ground  0V Ground pins 
Table 3 shows how the reset and clock signals are mapped to support each of the bifurcation cases 
for PCIe to the tray mezzanine. 
Table 3: PCIe bifurcation mapping 
 1 x 16 2 x 8 4 x 4 
 Signal name 15:0 15:8 7:0 15:12 11:8 7:4 3:0 
PCIE_RESET_N[0] X X  X    
PCIE_RESET_N[1]   X  X   
PCIE_RESET_N[2]      X  
PCIE_RESET_N[3]       X 
CLK_100M_P/N[0] X X  X    
CLK_100M_P/N[1]   X  X   
CLK_100M_P/N[2]      X  
CLK_100M_P/N[3]       X 



Open Compute Project  Open CloudServer OCS Tray Mezzanine 
http://opencompute.org 5 
2.2 Connector Pinout 
Table 4 lists the pinout for the 160-pin connector on the tray mezzanine card that interfaces to the tray backplane. 
Table 4: Tray mezzanine connector pinout 
 
160 MEZZ_PRESENT_B1_N PCIE_WAKE_B1_N MEZZ_B1_SDA MEZZ_B1_EN MEZZ_B1_SCL P12_MEZZ P12_MEZZ P12V_MEZZ 153
152 PCIE_RESET_B1_N<3> PCIE_RESET_B1_N<1> PCIE_RESET_B1_N<0> PCIE_CFG_B1_ID0 PCIE_CFG_B1_ID1 GND GND P12V_MEZZ 145
144 CLK_100M_N<3> PCIE_RESET_B1_N<2> CLK_100M_N<2> GND CLK_100M_N<1> GND CLK_100M_N<0> P12V_MEZZ 137
136 CLK_100M_P<3> GND CLK_100M_P<2> GND CLK_100M_P<1> GND CLK_100M_P<0> GND 129
128 GND PCIE_B2T_TX_DN<8> GND PCIE_B2T_TX_DN<0> GND PCIE_T2B_RX_DN<8> GND PCIE_T2B_RX_DN<0> 121
120 GND PCIE_B2T_TX_DP<8> GND PCIE_B2T_TX_DP<0> GND PCIE_T2B_RX_DP<8> GND PCIE_T2B_RX_DP<0> 113
112 PCIE_B2T_TX_DN<9> GND PCIE_B2T_TX_DN<1> GND PCIE_T2B_RX_DN<9> GND PCIE_T2B_RX_DN<1> GND 105
104 PCIE_B2T_TX_DP<9> GND PCIE_B2T_TX_DP<1> GND PCIE_T2B_RX_DP<9> GND PCIE_T2B_RX_DP<1> GND 97
96 GND PCIE_B2T_TX_DN<10> GND PCIE_B2T_TX_DN<2> GND PCIE_T2B_RX_DN<10> GND PCIE_T2B_RX_DN<2> 89
88 GND PCIE_B2T_TX_DP<10> GND PCIE_B2T_TX_DP<2> GND PCIE_T2B_RX_DP<10> GND PCIE_T2B_RX_DP<2> 81
80 PCIE_B2T_TX_DN<11> GND PCIE_B2T_TX_DN<3> GND PCIE_T2B_RX_DN<11> GND PCIE_T2B_RX_DN<3> GND 73
72 PCIE_B2T_TX_DP<11> GND PCIE_B2T_TX_DP<3> GND PCIE_T2B_RX_DP<11> GND PCIE_T2B_RX_DP<3> GND 65
64 GND PCIE_B2T_TX_DN<12> GND PCIE_B2T_TX_DN<4> GND PCIE_T2B_RX_DN<12> GND PCIE_T2B_RX_DN<4> 57
56 GND PCIE_B2T_TX_DP<12> GND PCIE_B2T_TX_DP<4> GND PCIE_T2B_RX_DP<12> GND PCIE_T2B_RX_DP<4> 49
48 PCIE_B2T_TX_DN<13> GND PCIE_B2T_TX_DN<5> GND PCIE_T2B_RX_DN<13> GND PCIE_T2B_RX_DN<5> GND 41
40 PCIE_B2T_TX_DP<13> GND PCIE_B2T_TX_DP<5> GND PCIE_T2B_RX_DP<13> GND PCIE_T2B_RX_DP<5> GND 33
32 GND PCIE_B2T_TX_DN<14> GND PCIE_B2T_TX_DN<6> GND PCIE_T2B_RX_DN<14> GND PCIE_T2B_RX_DN<6> 25
24 GND PCIE_B2T_TX_DP<14> GND PCIE_B2T_TX_DP<6> GND PCIE_T2B_RX_DP<14> GND PCIE_T2B_RX_DP<6> 17
16 PCIE_B2T_TX_DN<15> GND PCIE_B2T_TX_DN<7> GND PCIE_T2B_RX_DN<15> GND PCIE_T2B_RX_DN<7> GND 9
8 PCIE_B2T_TX_DP<15> GND PCIE_B2T_TX_DP<7> GND PCIE_T2B_RX_DP<15> GND PCIE_T2B_RX_DP<7> GND 1



 
6 October 30, 2014 
2.3 Power 
The tray mezzanine accepts a conditioned 12V from the tray backplane through five pins on the 
SEAM connector. This makes it possible for an estimated 3A of 12V current (36W) to the 
mezzanine, assuming 50% derating at 95⁰C for the connector pins. Note that this describes the 
power capability only, and does not imply the supported thermal envelope. 
3 Mechanical Control Outline 
Figure 4 and Figure 5 show the mechanical control outline for Model A and Model B cards. Either 
model may be selected to develop a card. 
 
Figure 4: Drawing of Model A card 



Open Compute Project  Open CloudServer OCS Tray Mezzanine 
http://opencompute.org 7 
 
 
Figure 5: Drawing of Model B card 
4 CAD Model Capture 
Figure 6 and Figure 7 show views of Computer-Aided Design (CAD) captures of Model A and Model 
B cards plugged into side-by-side blades. 



 
8 October 30, 2014 
 
 
Figure 6: View from front of Model A and Model B plugged into side-by-side blades 
 
Figure 7: View from inside of Model A and Model B plugged into side-by-side blades 
5 Thermal Specification 
The mezzanine card is presented with an approaching airflow temperature of 70⁰C and a flow rate 
of 0.61m/s. No downstream airflow requirements are placed on the mezzanine card. 


Open Compute Project  Open CloudServer OCS Tray Mezzanine 
http://opencompute.org 9 
 
6 Standoffs and Screws for Assembly 
The mezzanine card manufacturer is required to provide standoffs and screws to assemble the 
mezzanine card to the tray backplane board. The standoffs are to be provided loose in a bag and 
secured during assembly of the card to the tray backplane. 